# T6G (Grand Teton) — schematic netlist excerpt (pin names and nets, part order shuffled) for the footprints in the layout excerpt that follows; sources: Cadence DE-HDL packaged netlist, KiCad conversion of 04192023_DAF0TMB3IC0_F0TG_MB_C_brd_V02_OCP.brd

PC475  Q_CAP  2.2UF 10V 10% X6S  pkg C0402  page 194 : A = PVDDCR_CPU0_P0_VCC1 ; B = GND
R5011  Q_RES  1K 1% EMPTY  pkg 0402LF  page 159 : A = PVDD11_S3_P1 ; B = I3C_SPD_DDRAF_CPU1_LVC1_SDA

(kicad_pcb
	(version 20260206)
	(generator "pcbnew")
	(generator_version "10.0")
	(general
		(thickness 1.6)
		(legacy_teardrops no)
	)
	(paper "A4")
	(title_block
		(title "04192023_DAF0TMB3IC0_F0TG_MB_C_brd_V02_OCP.brd")
		(comment 1 "Grand Teton / footprints 712-713 of 8354")
	)
	(layers
		(0 "F.Cu" signal "TOP")
		(4 "In1.Cu" signal "GND")
		(6 "In2.Cu" signal "IN1")
		(8 "In3.Cu" signal "GND1")
		(10 "In4.Cu" signal "IN2")
		(12 "In5.Cu" signal "GND2")
		(14 "In6.Cu" signal "IN3")
		(16 "In7.Cu" signal "GND3")
		(18 "In8.Cu" signal "VCC")
		(20 "In9.Cu" signal "VCC1")
		(22 "In10.Cu" signal "GND4")
		(24 "In11.Cu" signal "IN4")
		(26 "In12.Cu" signal "GND5")
		(28 "In13.Cu" signal "IN5")
		(30 "In14.Cu" signal "GND6")
		(32 "In15.Cu" signal "IN6")
		(34 "In16.Cu" signal "GND7")
		(2 "B.Cu" signal "BOTTOM")
		(9 "F.Adhes" user "F.Adhesive")
		(11 "B.Adhes" user "B.Adhesive")
		(13 "F.Paste" user "Package Geometry/Pastemask Top")
		(15 "B.Paste" user "Package Geometry/Pastemask Bottom")
		(5 "F.SilkS" user "Ref Des/Silkscreen Top")
		(7 "B.SilkS" user "Ref Des/Silkscreen Bottom")
		(1 "F.Mask" user "Board Geometry/Soldermask Top")
		(3 "B.Mask" user "Board Geometry/Soldermask Bottom")
		(17 "Dwgs.User" user "User.Drawings")
		(19 "Cmts.User" user "User.Comments")
		(21 "Eco1.User" user "User.Eco1")
		(23 "Eco2.User" user "User.Eco2")
		(25 "Edge.Cuts" user "Board Geometry/Outline")
		(27 "Margin" user)
		(31 "F.CrtYd" user "Package Geometry/Place Bound Top")
		(29 "B.CrtYd" user "Package Geometry/Place Bound Bottom")
		(35 "F.Fab" user "Ref Des/Assembly Top")
		(33 "B.Fab" user "Ref Des/Assembly Bottom")
	)
	(footprint ""
		(layer "F.Cu")
		(at 34.665158 -172.53966)
		(property "Reference" "R5011"
			(at 0 0 0)
			(layer "F.SilkS")
			(hide yes)
			(effects
				(font
					(size 1.27 1.27)
				)
			)
		)
		(property "Value" ""
			(at 0 0 0)
			(layer "F.Fab")
			(effects
				(font
					(size 1.27 1.27)
				)
			)
		)
		(duplicate_pad_numbers_are_jumpers no)
		(fp_line
			(start -0.7874 -0.4064)
			(end 0.7874 -0.4064)
			(stroke
				(width 0.1524)
				(type default)
			)
			(layer "F.SilkS")
		)
		(fp_line
			(start -0.7874 0.4064)
			(end -0.7874 -0.4064)
			(stroke
				(width 0.1524)
				(type default)
			)
			(layer "F.SilkS")
		)
		(fp_line
			(start 0.7874 -0.4064)
			(end 0.7874 0.4064)
			(stroke
				(width 0.1524)
				(type default)
			)
			(layer "F.SilkS")
		)
		(fp_line
			(start 0.7874 0.4064)
			(end -0.7874 0.4064)
			(stroke
				(width 0.1524)
				(type default)
			)
			(layer "F.SilkS")
		)
		(fp_line
			(start -0.67945 -0.305054)
			(end -0.12065 -0.305054)
			(stroke
				(width 0.1)
				(type default)
			)
			(layer "F.Fab")
		)
		(fp_line
			(start -0.67945 0.3048)
			(end -0.67945 -0.305054)
			(stroke
				(width 0.1)
				(type default)
			)
			(layer "F.Fab")
		)
		(fp_line
			(start -0.12065 -0.305054)
			(end -0.12065 -0.2794)
			(stroke
				(width 0.1)
				(type default)
			)
			(layer "F.Fab")
		)
		(fp_line
			(start -0.12065 -0.2794)
			(end 0.12065 -0.2794)
			(stroke
				(width 0.1)
				(type default)
			)
			(layer "F.Fab")
		)
		(fp_line
			(start -0.12065 0.2794)
			(end -0.12065 0.3048)
			(stroke
				(width 0.1)
				(type default)
			)
			(layer "F.Fab")
		)
		(fp_line
			(start -0.12065 0.3048)
			(end -0.67945 0.3048)
			(stroke
				(width 0.1)
				(type default)
			)
			(layer "F.Fab")
		)
		(fp_line
			(start 0.120396 0.2794)
			(end -0.12065 0.2794)
			(stroke
				(width 0.1)
				(type default)
			)
			(layer "F.Fab")
		)
		(fp_line
			(start 0.120396 0.3048)
			(end 0.120396 0.2794)
			(stroke
				(width 0.1)
				(type default)
			)
			(layer "F.Fab")
		)
		(fp_line
			(start 0.12065 -0.3048)
			(end 0.67945 -0.3048)
			(stroke
				(width 0.1)
				(type default)
			)
			(layer "F.Fab")
		)
		(fp_line
			(start 0.12065 -0.2794)
			(end 0.12065 -0.3048)
			(stroke
				(width 0.1)
				(type default)
			)
			(layer "F.Fab")
		)
		(fp_line
			(start 0.67945 -0.3048)
			(end 0.67945 0.3048)
			(stroke
				(width 0.1)
				(type default)
			)
			(layer "F.Fab")
		)
		(fp_line
			(start 0.67945 0.3048)
			(end 0.120396 0.3048)
			(stroke
				(width 0.1)
				(type default)
			)
			(layer "F.Fab")
		)
		(pad "1" smd circle
			(at -0.40005 0)
			(size 0 0)
			(layers "F.Cu" "F.Mask" "F.Paste")
			(net "PVDD11_S3_P1")
		)
		(pad "2" smd circle
			(at 0.40005 0)
			(size 0 0)
			(layers "F.Cu" "F.Mask" "F.Paste")
			(net "I3C_SPD_DDRAF_CPU1_LVC1_SDA")
		)
	)
	(footprint ""
		(layer "F.Cu")
		(at 367.996978 -175.106076 -90)
		(property "Reference" "PC475"
			(at 0 0 270)
			(layer "F.SilkS")
			(hide yes)
			(effects
				(font
					(size 1.27 1.27)
				)
			)
		)
		(property "Value" ""
			(at 0 0 270)
			(layer "F.Fab")
			(effects
				(font
					(size 1.27 1.27)
				)
			)
		)
		(duplicate_pad_numbers_are_jumpers no)
		(fp_line
			(start -0.7874 0.4064)
			(end -0.7874 -0.4064)
			(stroke
				(width 0.1524)
				(type default)
			)
			(layer "F.SilkS")
		)
		(fp_line
			(start -0.255524 0.4064)
			(end -0.7874 0.4064)
			(stroke
				(width 0.1524)
				(type default)
			)
			(layer "F.SilkS")
		)
		(fp_line
			(start 0.7874 0.4064)
			(end 0.404876 0.4064)
			(stroke
				(width 0.1524)
				(type default)
			)
			(layer "F.SilkS")
		)
		(fp_line
			(start -0.7874 -0.4064)
			(end 0.7874 -0.4064)
			(stroke
				(width 0.1524)
				(type default)
			)
			(layer "F.SilkS")
		)
		(fp_line
			(start 0.7874 -0.4064)
			(end 0.7874 0.4064)
			(stroke
				(width 0.1524)
				(type default)
			)
			(layer "F.SilkS")
		)
		(fp_line
			(start -0.67945 0.3048)
			(end -0.67945 -0.305054)
			(stroke
				(width 0.1)
				(type default)
			)
			(layer "F.Fab")
		)
		(fp_line
			(start -0.12065 0.3048)
			(end -0.67945 0.3048)
			(stroke
				(width 0.1)
				(type default)
			)
			(layer "F.Fab")
		)
		(fp_line
			(start 0.120396 0.3048)
			(end 0.120396 0.2794)
			(stroke
				(width 0.1)
				(type default)
			)
			(layer "F.Fab")
		)
		(fp_line
			(start 0.67945 0.3048)
			(end 0.120396 0.3048)
			(stroke
				(width 0.1)
				(type default)
			)
			(layer "F.Fab")
		)
		(fp_line
			(start -0.12065 0.2794)
			(end -0.12065 0.3048)
			(stroke
				(width 0.1)
				(type default)
			)
			(layer "F.Fab")
		)
		(fp_line
			(start 0.120396 0.2794)
			(end -0.12065 0.2794)
			(stroke
				(width 0.1)
				(type default)
			)
			(layer "F.Fab")
		)
		(fp_line
			(start -0.12065 -0.2794)
			(end 0.12065 -0.2794)
			(stroke
				(width 0.1)
				(type default)
			)
			(layer "F.Fab")
		)
		(fp_line
			(start 0.12065 -0.2794)
			(end 0.12065 -0.3048)
			(stroke
				(width 0.1)
				(type default)
			)
			(layer "F.Fab")
		)
		(fp_line
			(start 0.12065 -0.3048)
			(end 0.67945 -0.3048)
			(stroke
				(width 0.1)
				(type default)
			)
			(layer "F.Fab")
		)
		(fp_line
			(start 0.67945 -0.3048)
			(end 0.67945 0.3048)
			(stroke
				(width 0.1)
				(type default)
			)
			(layer "F.Fab")
		)
		(fp_line
			(start -0.67945 -0.305054)
			(end -0.12065 -0.305054)
			(stroke
				(width 0.1)
				(type default)
			)
			(layer "F.Fab")
		)
		(fp_line
			(start -0.12065 -0.305054)
			(end -0.12065 -0.2794)
			(stroke
				(width 0.1)
				(type default)
			)
			(layer "F.Fab")
		)
		(pad "1" smd circle
			(at -0.40005 0 270)
			(size 0 0)
			(layers "F.Cu" "F.Mask" "F.Paste")
			(net "PVDDCR_CPU0_P0_VCC1")
		)
		(pad "2" smd circle
			(at 0.40005 0 270)
			(size 0 0)
			(layers "F.Cu" "F.Mask" "F.Paste")
			(net "GND")
		)
	)
)
